(kicad_pcb
	(version 20260206)
	(generator "pcbnew")
	(generator_version "10.0")
	(general
		(thickness 1.6)
		(legacy_teardrops no)
	)
	(paper "A4")
	(title_block
		(title "peb — Lightning_PEB_BRD.brd")
		(comment 1 "Lightning (Wiwynn / Facebook NVMe JBOF) / footprints 87-92 of 2563")
	)
	(layers
		(0 "F.Cu" signal "TOP")
		(4 "In1.Cu" signal "L2GND")
		(6 "In2.Cu" signal "L3")
		(8 "In3.Cu" signal "L4VCC")
		(10 "In4.Cu" signal "L5VCC")
		(12 "In5.Cu" signal "L6")
		(14 "In6.Cu" signal "L7GND")
		(2 "B.Cu" signal "BOTTOM")
		(9 "F.Adhes" user "F.Adhesive")
		(11 "B.Adhes" user "B.Adhesive")
		(13 "F.Paste" user "Package Geometry/Pastemask Top")
		(15 "B.Paste" user "Package Geometry/Pastemask Bottom")
		(5 "F.SilkS" user "Ref Des/Silkscreen Top")
		(7 "B.SilkS" user "Ref Des/Silkscreen Bottom")
		(1 "F.Mask" user "Board Geometry/Soldermask Top")
		(3 "B.Mask" user "Board Geometry/Soldermask Bottom")
		(17 "Dwgs.User" user "User.Drawings")
		(19 "Cmts.User" user "User.Comments")
		(21 "Eco1.User" user "User.Eco1")
		(23 "Eco2.User" user "User.Eco2")
		(25 "Edge.Cuts" user "Board Geometry/Outline")
		(27 "Margin" user)
		(31 "F.CrtYd" user "Package Geometry/Place Bound Top")
		(29 "B.CrtYd" user "Package Geometry/Place Bound Bottom")
		(35 "F.Fab" user "Ref Des/Assembly Top")
		(33 "B.Fab" user "Ref Des/Assembly Bottom")
	)
	(footprint ""
		(layer "F.Cu")
		(at 172.593 -53.848 -90)
		(property "Reference" "R558"
			(at 0 0 270)
			(layer "F.SilkS")
			(hide yes)
			(effects
				(font
					(size 1.27 1.27)
				)
			)
		)
		(property "Value" "0R2J-2-GP"
			(at 0.064008 -3.993896 270)
			(unlocked yes)
			(layer "F.Fab")
			(hide yes)
			(effects
				(font
					(size 1.016 1.016)
					(thickness 0.1524)
				)
			)
		)
		(property "Device Type" "R402H16"
			(at 0.064008 -5.517896 270)
			(unlocked yes)
			(layer "F.Fab")
			(hide yes)
			(effects
				(font
					(size 1.016 1.016)
					(thickness 0.1524)
				)
			)
		)
		(duplicate_pad_numbers_are_jumpers no)
		(fp_line
			(start -0.508 -0.9398)
			(end -0.508 0.9398)
			(stroke
				(width 0.1524)
				(type default)
			)
			(layer "F.SilkS")
		)
		(fp_line
			(start 0.508 -0.9398)
			(end -0.508 -0.9398)
			(stroke
				(width 0.1524)
				(type default)
			)
			(layer "F.SilkS")
		)
		(fp_rect
			(start -0.508 0.9398)
			(end 0.508 -0.9398)
			(stroke
				(width 0)
				(type default)
			)
			(fill no)
			(layer "F.CrtYd")
		)
		(fp_rect
			(start -0.508 0.9398)
			(end 0.508 -0.9398)
			(stroke
				(width 0)
				(type default)
			)
			(fill no)
			(layer "F.Fab")
		)
		(pad "1" smd custom
			(at 0 -0.4445 270)
			(size 0.1397 0.1397)
			(layers "F.Cu" "F.Mask" "F.Paste")
			(net "VS2_LED_R")
			(options
				(clearance outline)
				(anchor circle)
			)
			(primitives
				(gr_poly
					(pts
						(arc
							(start -0.1778 -0.2794)
							(mid -0.249642 -0.249642)
							(end -0.2794 -0.1778)
						)
						(arc
							(start -0.2794 0.1778)
							(mid -0.249642 0.249642)
							(end -0.1778 0.2794)
						)
						(arc
							(start 0.1778 0.2794)
							(mid 0.249642 0.249642)
							(end 0.2794 0.1778)
						)
						(arc
							(start 0.2794 -0.1778)
							(mid 0.249642 -0.249642)
							(end 0.1778 -0.2794)
						)
					)
					(width 0)
					(fill yes)
				)
			)
		)
		(pad "2" smd custom
			(at 0 0.4445 270)
			(size 0.1397 0.1397)
			(layers "F.Cu" "F.Mask" "F.Paste")
			(net "VS2_LED")
			(options
				(clearance outline)
				(anchor circle)
			)
			(primitives
				(gr_poly
					(pts
						(arc
							(start -0.1778 -0.2794)
							(mid -0.249642 -0.249642)
							(end -0.2794 -0.1778)
						)
						(arc
							(start -0.2794 0.1778)
							(mid -0.249642 0.249642)
							(end -0.1778 0.2794)
						)
						(arc
							(start 0.1778 0.2794)
							(mid 0.249642 0.249642)
							(end 0.2794 0.1778)
						)
						(arc
							(start 0.2794 -0.1778)
							(mid 0.249642 -0.249642)
							(end 0.1778 -0.2794)
						)
					)
					(width 0)
					(fill yes)
				)
			)
		)
	)
	(footprint ""
		(layer "F.Cu")
		(at 192.9384 -23.0124 -90)
		(property "Reference" "R838"
			(at 0 0 270)
			(layer "F.SilkS")
			(hide yes)
			(effects
				(font
					(size 1.27 1.27)
				)
			)
		)
		(property "Value" "4K7R2F-GP"
			(at 0.064008 -3.993896 270)
			(unlocked yes)
			(layer "F.Fab")
			(hide yes)
			(effects
				(font
					(size 1.016 1.016)
					(thickness 0.1524)
				)
			)
		)
		(property "Device Type" "R402H16"
			(at 0.064008 -5.517896 270)
			(unlocked yes)
			(layer "F.Fab")
			(hide yes)
			(effects
				(font
					(size 1.016 1.016)
					(thickness 0.1524)
				)
			)
		)
		(duplicate_pad_numbers_are_jumpers no)
		(fp_line
			(start -0.508 -0.9398)
			(end -0.508 0.9398)
			(stroke
				(width 0.1524)
				(type default)
			)
			(layer "F.SilkS")
		)
		(fp_line
			(start 0.508 -0.9398)
			(end -0.508 -0.9398)
			(stroke
				(width 0.1524)
				(type default)
			)
			(layer "F.SilkS")
		)
		(fp_rect
			(start -0.508 0.9398)
			(end 0.508 -0.9398)
			(stroke
				(width 0)
				(type default)
			)
			(fill no)
			(layer "F.CrtYd")
		)
		(fp_rect
			(start -0.508 0.9398)
			(end 0.508 -0.9398)
			(stroke
				(width 0)
				(type default)
			)
			(fill no)
			(layer "F.Fab")
		)
		(pad "1" smd custom
			(at 0 -0.4445 270)
			(size 0.1397 0.1397)
			(layers "F.Cu" "F.Mask" "F.Paste")
			(net "U56_A2")
			(options
				(clearance outline)
				(anchor circle)
			)
			(primitives
				(gr_poly
					(pts
						(arc
							(start -0.1778 -0.2794)
							(mid -0.249642 -0.249642)
							(end -0.2794 -0.1778)
						)
						(arc
							(start -0.2794 0.1778)
							(mid -0.249642 0.249642)
							(end -0.1778 0.2794)
						)
						(arc
							(start 0.1778 0.2794)
							(mid 0.249642 0.249642)
							(end 0.2794 0.1778)
						)
						(arc
							(start 0.2794 -0.1778)
							(mid 0.249642 -0.249642)
							(end 0.1778 -0.2794)
						)
					)
					(width 0)
					(fill yes)
				)
			)
		)
		(pad "2" smd custom
			(at 0 0.4445 270)
			(size 0.1397 0.1397)
			(layers "F.Cu" "F.Mask" "F.Paste")
			(net "P3V3_STBY")
			(options
				(clearance outline)
				(anchor circle)
			)
			(primitives
				(gr_poly
					(pts
						(arc
							(start -0.1778 -0.2794)
							(mid -0.249642 -0.249642)
							(end -0.2794 -0.1778)
						)
						(arc
							(start -0.2794 0.1778)
							(mid -0.249642 0.249642)
							(end -0.1778 0.2794)
						)
						(arc
							(start 0.1778 0.2794)
							(mid 0.249642 0.249642)
							(end 0.2794 0.1778)
						)
						(arc
							(start 0.2794 -0.1778)
							(mid 0.249642 -0.249642)
							(end 0.1778 -0.2794)
						)
					)
					(width 0)
					(fill yes)
				)
			)
		)
	)
	(footprint ""
		(layer "F.Cu")
		(at 21.405596 -101.813614)
		(property "Reference" "R2946"
			(at 0 0 0)
			(layer "F.SilkS")
			(hide yes)
			(effects
				(font
					(size 1.27 1.27)
				)
			)
		)
		(property "Value" "10KR2F-2-GP"
			(at 0.064008 -3.993896 0)
			(unlocked yes)
			(layer "F.Fab")
			(hide yes)
			(effects
				(font
					(size 1.016 1.016)
					(thickness 0.1524)
				)
			)
		)
		(property "Device Type" "R402H16"
			(at 0.064008 -5.517896 0)
			(unlocked yes)
			(layer "F.Fab")
			(hide yes)
			(effects
				(font
					(size 1.016 1.016)
					(thickness 0.1524)
				)
			)
		)
		(duplicate_pad_numbers_are_jumpers no)
		(fp_line
			(start -0.508 -0.9398)
			(end -0.508 0.9398)
			(stroke
				(width 0.1524)
				(type default)
			)
			(layer "F.SilkS")
		)
		(fp_line
			(start 0.508 -0.9398)
			(end -0.508 -0.9398)
			(stroke
				(width 0.1524)
				(type default)
			)
			(layer "F.SilkS")
		)
		(fp_rect
			(start -0.508 0.9398)
			(end 0.508 -0.9398)
			(stroke
				(width 0)
				(type default)
			)
			(fill no)
			(layer "F.CrtYd")
		)
		(fp_rect
			(start -0.508 0.9398)
			(end 0.508 -0.9398)
			(stroke
				(width 0)
				(type default)
			)
			(fill no)
			(layer "F.Fab")
		)
		(pad "1" smd custom
			(at 0 -0.4445)
			(size 0.1397 0.1397)
			(layers "F.Cu" "F.Mask" "F.Paste")
			(net "VREF_2V2")
			(options
				(clearance outline)
				(anchor circle)
			)
			(primitives
				(gr_poly
					(pts
						(arc
							(start -0.1778 -0.2794)
							(mid -0.249642 -0.249642)
							(end -0.2794 -0.1778)
						)
						(arc
							(start -0.2794 0.1778)
							(mid -0.249642 0.249642)
							(end -0.1778 0.2794)
						)
						(arc
							(start 0.1778 0.2794)
							(mid 0.249642 0.249642)
							(end 0.2794 0.1778)
						)
						(arc
							(start 0.2794 -0.1778)
							(mid 0.249642 -0.249642)
							(end 0.1778 -0.2794)
						)
					)
					(width 0)
					(fill yes)
				)
			)
		)
		(pad "2" smd custom
			(at 0 0.4445)
			(size 0.1397 0.1397)
			(layers "F.Cu" "F.Mask" "F.Paste")
			(net "GND")
			(options
				(clearance outline)
				(anchor circle)
			)
			(primitives
				(gr_poly
					(pts
						(arc
							(start -0.1778 -0.2794)
							(mid -0.249642 -0.249642)
							(end -0.2794 -0.1778)
						)
						(arc
							(start -0.2794 0.1778)
							(mid -0.249642 0.249642)
							(end -0.1778 0.2794)
						)
						(arc
							(start 0.1778 0.2794)
							(mid 0.249642 0.249642)
							(end 0.2794 0.1778)
						)
						(arc
							(start 0.2794 -0.1778)
							(mid 0.249642 -0.249642)
							(end 0.1778 -0.2794)
						)
					)
					(width 0)
					(fill yes)
				)
			)
		)
	)
	(footprint ""
		(layer "F.Cu")
		(at 69.2658 -126.6952 -90)
		(property "Reference" "U45"
			(at 0 0 270)
			(layer "F.SilkS")
			(hide yes)
			(effects
				(font
					(size 1.27 1.27)
				)
			)
		)
		(property "Value" "SN74AUP1T97DCKR-GP"
			(at -2.3622 -8.2042 270)
			(unlocked yes)
			(layer "F.Fab")
			(hide yes)
			(effects
				(font
					(size 1.016 1.016)
					(thickness 0.1524)
				)
			)
		)
		(property "Device Type" "SC70-6H44"
			(at -2.3622 -10.1092 270)
			(unlocked yes)
			(layer "F.Fab")
			(hide yes)
			(effects
				(font
					(size 1.016 1.016)
					(thickness 0.1524)
				)
			)
		)
		(duplicate_pad_numbers_are_jumpers no)
		(fp_line
			(start -1.5494 1.7907)
			(end -1.5494 0.8255)
			(stroke
				(width 0.3302)
				(type default)
			)
			(layer "F.SilkS")
		)
		(fp_line
			(start -0.5715 1.7907)
			(end -1.5494 1.7907)
			(stroke
				(width 0.3302)
				(type default)
			)
			(layer "F.SilkS")
		)
		(fp_line
			(start -1.4478 1.7018)
			(end 1.4478 1.7018)
			(stroke
				(width 0.1524)
				(type default)
			)
			(layer "F.SilkS")
		)
		(fp_line
			(start 1.4478 1.7018)
			(end 1.4478 -1.7018)
			(stroke
				(width 0.1524)
				(type default)
			)
			(layer "F.SilkS")
		)
		(fp_line
			(start -1.4478 -1.7018)
			(end -1.4478 1.7018)
			(stroke
				(width 0.1524)
				(type default)
			)
			(layer "F.SilkS")
		)
		(fp_line
			(start 1.4478 -1.7018)
			(end -1.4478 -1.7018)
			(stroke
				(width 0.1524)
				(type default)
			)
			(layer "F.SilkS")
		)
		(fp_poly
			(pts
				(xy -0.6604 1.7272) (xy -1.016 2.0828) (xy -0.3048 2.0828)
			)
			(stroke
				(width 0)
				(type default)
			)
			(fill yes)
			(layer "F.SilkS")
		)
		(fp_poly
			(pts
				(xy -1.524 -1.778) (xy 1.524 -1.778) (xy 1.524 1.778) (xy -1.524 1.778)
			)
			(stroke
				(width 0)
				(type default)
			)
			(fill no)
			(layer "F.CrtYd")
		)
		(fp_poly
			(pts
				(xy -1.524 -1.778) (xy 1.524 -1.778) (xy 1.524 1.778) (xy -1.524 1.778)
			)
			(stroke
				(width 0)
				(type default)
			)
			(fill no)
			(layer "F.Fab")
		)
		(pad "1" smd rect
			(at -0.65024 0.9398 270)
			(size 0.4064 1.016)
			(layers "F.Cu" "F.Mask" "F.Paste")
			(net "BMC_TXD5_R")
		)
		(pad "2" smd rect
			(at 0 0.9398 270)
			(size 0.4064 1.016)
			(layers "F.Cu" "F.Mask" "F.Paste")
			(net "GND")
		)
		(pad "3" smd rect
			(at 0.65024 0.9398 270)
			(size 0.4064 1.016)
			(layers "F.Cu" "F.Mask" "F.Paste")
			(net "GND")
		)
		(pad "4" smd rect
			(at 0.65024 -0.9398 270)
			(size 0.4064 1.016)
			(layers "F.Cu" "F.Mask" "F.Paste")
			(net "MBP_UART_TX")
		)
		(pad "5" smd rect
			(at 0 -0.9398 270)
			(size 0.4064 1.016)
			(layers "F.Cu" "F.Mask" "F.Paste")
			(net "P3V3_STBY")
		)
		(pad "6" smd rect
			(at -0.65024 -0.9398 270)
			(size 0.4064 1.016)
			(layers "F.Cu" "F.Mask" "F.Paste")
			(net "GND")
		)
	)
	(footprint ""
		(layer "F.Cu")
		(at 53.594 -134.62 -90)
		(property "Reference" "R338"
			(at 0 0 270)
			(layer "F.SilkS")
			(hide yes)
			(effects
				(font
					(size 1.27 1.27)
				)
			)
		)
		(property "Value" "2K74R3F-GP"
			(at -0.0254 -2.5146 270)
			(unlocked yes)
			(layer "F.Fab")
			(hide yes)
			(effects
				(font
					(size 1.016 1.016)
					(thickness 0.1524)
				)
			)
		)
		(property "Device Type" "R603H22"
			(at -0.0254 -4.0386 270)
			(unlocked yes)
			(layer "F.Fab")
			(hide yes)
			(effects
				(font
					(size 1.016 1.016)
					(thickness 0.1524)
				)
			)
		)
		(duplicate_pad_numbers_are_jumpers no)
		(fp_line
			(start -0.4826 0)
			(end -0.2032 0)
			(stroke
				(width 0.2032)
				(type default)
			)
			(layer "F.SilkS")
		)
		(fp_line
			(start 0.2032 0)
			(end 0.4826 0)
			(stroke
				(width 0.2032)
				(type default)
			)
			(layer "F.SilkS")
		)
		(fp_rect
			(start -0.5842 1.3335)
			(end 0.5842 -1.3335)
			(stroke
				(width 0)
				(type default)
			)
			(fill no)
			(layer "F.CrtYd")
		)
		(fp_rect
			(start -0.5842 1.3335)
			(end 0.5842 -1.3335)
			(stroke
				(width 0)
				(type default)
			)
			(fill no)
			(layer "F.Fab")
		)
		(pad "1" smd custom
			(at 0 -0.762 270)
			(size 0.2159 0.2159)
			(layers "F.Cu" "F.Mask" "F.Paste")
			(net "GND")
			(options
				(clearance outline)
				(anchor circle)
			)
			(primitives
				(gr_poly
					(pts
						(arc
							(start -0.3302 -0.4318)
							(mid -0.402042 -0.402042)
							(end -0.4318 -0.3302)
						)
						(arc
							(start -0.4318 0.3302)
							(mid -0.402042 0.402042)
							(end -0.3302 0.4318)
						)
						(arc
							(start 0.3302 0.4318)
							(mid 0.402042 0.402042)
							(end 0.4318 0.3302)
						)
						(arc
							(start 0.4318 -0.3302)
							(mid 0.402042 -0.402042)
							(end 0.3302 -0.4318)
						)
					)
					(width 0)
					(fill yes)
				)
			)
		)
		(pad "2" smd custom
			(at 0 0.762 270)
			(size 0.2159 0.2159)
			(layers "F.Cu" "F.Mask" "F.Paste")
			(net "DACRSET")
			(options
				(clearance outline)
				(anchor circle)
			)
			(primitives
				(gr_poly
					(pts
						(arc
							(start -0.3302 -0.4318)
							(mid -0.402042 -0.402042)
							(end -0.4318 -0.3302)
						)
						(arc
							(start -0.4318 0.3302)
							(mid -0.402042 0.402042)
							(end -0.3302 0.4318)
						)
						(arc
							(start 0.3302 0.4318)
							(mid 0.402042 0.402042)
							(end 0.4318 0.3302)
						)
						(arc
							(start 0.4318 -0.3302)
							(mid 0.402042 -0.402042)
							(end 0.3302 -0.4318)
						)
					)
					(width 0)
					(fill yes)
				)
			)
		)
	)
	(footprint ""
		(layer "F.Cu")
		(at 262.382 -17.272 180)
		(property "Reference" "R715"
			(at 0 0 180)
			(layer "F.SilkS")
			(hide yes)
			(effects
				(font
					(size 1.27 1.27)
				)
			)
		)
		(property "Value" "4K7R2F-GP"
			(at 0.064008 -3.993896 180)
			(unlocked yes)
			(layer "F.Fab")
			(hide yes)
			(effects
				(font
					(size 1.016 1.016)
					(thickness 0.1524)
				)
			)
		)
		(property "Device Type" "R402H16"
			(at 0.064008 -5.517896 180)
			(unlocked yes)
			(layer "F.Fab")
			(hide yes)
			(effects
				(font
					(size 1.016 1.016)
					(thickness 0.1524)
				)
			)
		)
		(duplicate_pad_numbers_are_jumpers no)
		(fp_line
			(start 0.508 -0.9398)
			(end -0.508 -0.9398)
			(stroke
				(width 0.1524)
				(type default)
			)
			(layer "F.SilkS")
		)
		(fp_line
			(start -0.508 -0.9398)
			(end -0.508 0.9398)
			(stroke
				(width 0.1524)
				(type default)
			)
			(layer "F.SilkS")
		)
		(fp_rect
			(start -0.508 0.9398)
			(end 0.508 -0.9398)
			(stroke
				(width 0)
				(type default)
			)
			(fill no)
			(layer "F.CrtYd")
		)
		(fp_rect
			(start -0.508 0.9398)
			(end 0.508 -0.9398)
			(stroke
				(width 0)
				(type default)
			)
			(fill no)
			(layer "F.Fab")
		)
		(pad "1" smd custom
			(at 0 -0.4445 180)
			(size 0.1397 0.1397)
			(layers "F.Cu" "F.Mask" "F.Paste")
			(net "Q40_D")
			(options
				(clearance outline)
				(anchor circle)
			)
			(primitives
				(gr_poly
					(pts
						(arc
							(start -0.1778 -0.2794)
							(mid -0.249642 -0.249642)
							(end -0.2794 -0.1778)
						)
						(arc
							(start -0.2794 0.1778)
							(mid -0.249642 0.249642)
							(end -0.1778 0.2794)
						)
						(arc
							(start 0.1778 0.2794)
							(mid 0.249642 0.249642)
							(end 0.2794 0.1778)
						)
						(arc
							(start 0.2794 -0.1778)
							(mid 0.249642 -0.249642)
							(end 0.1778 -0.2794)
						)
					)
					(width 0)
					(fill yes)
				)
			)
		)
		(pad "2" smd custom
			(at 0 0.4445 180)
			(size 0.1397 0.1397)
			(layers "F.Cu" "F.Mask" "F.Paste")
			(net "Q3203_G")
			(options
				(clearance outline)
				(anchor circle)
			)
			(primitives
				(gr_poly
					(pts
						(arc
							(start -0.1778 -0.2794)
							(mid -0.249642 -0.249642)
							(end -0.2794 -0.1778)
						)
						(arc
							(start -0.2794 0.1778)
							(mid -0.249642 0.249642)
							(end -0.1778 0.2794)
						)
						(arc
							(start 0.1778 0.2794)
							(mid 0.249642 0.249642)
							(end 0.2794 0.1778)
						)
						(arc
							(start 0.2794 -0.1778)
							(mid 0.249642 -0.249642)
							(end 0.1778 -0.2794)
						)
					)
					(width 0)
					(fill yes)
				)
			)
		)
	)
)
